(kicad_pcb
	(version 20260206)
	(generator "pcbnew")
	(generator_version "10.0")
	(general
		(thickness 1.6)
		(legacy_teardrops no)
	)
	(paper "A4")
	(title_block
		(title "panther-plus-userver — 13130-1b_20150205.brd")
		(comment 1 "Honey Badger (Wiwynn) / footprint 1214 of 1509 (DIMM3), pads 205-210 of 210")
	)
	(layers
		(0 "F.Cu" signal "TOP")
		(4 "In1.Cu" signal "L2")
		(6 "In2.Cu" signal "L3")
		(8 "In3.Cu" signal "L4")
		(10 "In4.Cu" signal "L5")
		(12 "In5.Cu" signal "L6")
		(14 "In6.Cu" signal "L7")
		(16 "In7.Cu" signal "L8")
		(18 "In8.Cu" signal "L9")
		(20 "In9.Cu" signal "L10")
		(22 "In10.Cu" signal "L11")
		(2 "B.Cu" signal "BOTTOM")
		(9 "F.Adhes" user "F.Adhesive")
		(11 "B.Adhes" user "B.Adhesive")
		(13 "F.Paste" user "Package Geometry/Pastemask Top")
		(15 "B.Paste" user "Package Geometry/Pastemask Bottom")
		(5 "F.SilkS" user "Ref Des/Silkscreen Top")
		(7 "B.SilkS" user "Ref Des/Silkscreen Bottom")
		(1 "F.Mask" user "Board Geometry/Soldermask Top")
		(3 "B.Mask" user "Board Geometry/Soldermask Bottom")
		(17 "Dwgs.User" user "User.Drawings")
		(19 "Cmts.User" user "User.Comments")
		(21 "Eco1.User" user "User.Eco1")
		(23 "Eco2.User" user "User.Eco2")
		(25 "Edge.Cuts" user "Board Geometry/Outline")
		(27 "Margin" user)
		(31 "F.CrtYd" user "Package Geometry/Place Bound Top")
		(29 "B.CrtYd" user "Package Geometry/Place Bound Bottom")
		(35 "F.Fab" user "Ref Des/Assembly Top")
		(33 "B.Fab" user "Ref Des/Assembly Bottom")
	)
	(footprint ""
		(layer "B.Cu")
		(at 159.999934 -5.790692)
		(property "Reference" "DIMM3"
			(at 0 0 0)
			(layer "B.SilkS")
			(hide yes)
			(effects
				(font
					(size 1.27 1.27)
				)
				(justify mirror)
			)
		)
		(property "Value" "DDR3-204P-142-COLAY-1-GP-U"
			(at 41.312338 -16.676878 0)
			(unlocked yes)
			(layer "B.Fab")
			(hide yes)
			(effects
				(font
					(size 1.016 1.016)
					(thickness 0.1524)
				)
				(justify mirror)
			)
		)
		(property "Device Type" "AS0A626-J8R6-7H-COLAY-1"
			(at 41.312338 -18.200878 0)
			(unlocked yes)
			(layer "B.Fab")
			(hide yes)
			(effects
				(font
					(size 1.016 1.016)
					(thickness 0.1524)
				)
				(justify mirror)
			)
		)
		(duplicate_pad_numbers_are_jumpers no)
		(pad "203" smd custom
			(at 31.34995 -4.100068 180)
			(size 0.1143 0.1143)
			(layers "B.Cu" "B.Mask" "B.Paste")
			(net "PV_VTT_DDR_B")
			(options
				(clearance outline)
				(anchor circle)
			)
			(primitives
				(gr_poly
					(pts
						(xy 0 -0.9017) (xy -0.03175 -0.89916) (xy -0.0635 -0.889) (xy -0.09144 -0.87376) (xy -0.11684 -0.85344)
						(xy -0.13716 -0.82804) (xy -0.1524 -0.8001) (xy -0.16256 -0.76835) (xy -0.1651 -0.7366) (xy -0.1651 -0.19685)
						(xy -0.17272 -0.18923) (xy -0.17907 -0.18034) (xy -0.18669 -0.17145) (xy -0.19177 -0.16256) (xy -0.19812 -0.15367)
						(xy -0.20828 -0.13335) (xy -0.21971 -0.10287) (xy -0.22225 -0.09271) (xy -0.22479 -0.08128) (xy -0.22606 -0.07112)
						(xy -0.2286 -0.05969) (xy -0.2286 -0.01651) (xy -0.22606 -0.00508) (xy -0.22479 0.00508) (xy -0.22225 0.01651)
						(xy -0.21971 0.02667) (xy -0.20828 0.05715) (xy -0.19812 0.07747) (xy -0.19177 0.08636) (xy -0.18669 0.09525)
						(xy -0.17907 0.10414) (xy -0.17272 0.11303) (xy -0.1651 0.12065) (xy -0.1651 0.7366) (xy -0.16256 0.76835)
						(xy -0.1524 0.8001) (xy -0.13716 0.82804) (xy -0.11684 0.85344) (xy -0.09144 0.87376) (xy -0.0635 0.889)
						(xy -0.03175 0.89916) (xy 0 0.9017) (xy 0.03175 0.89916) (xy 0.0635 0.889) (xy 0.09144 0.87376)
						(xy 0.11684 0.85344) (xy 0.13716 0.82804) (xy 0.1524 0.8001) (xy 0.16256 0.76835) (xy 0.1651 0.7366)
						(xy 0.1651 0.11938) (xy 0.17272 0.11176) (xy 0.19812 0.0762) (xy 0.2032 0.06604) (xy 0.20701 0.05715)
						(xy 0.21209 0.04699) (xy 0.2159 0.03683) (xy 0.21844 0.02667) (xy 0.22225 0.01524) (xy 0.22352 0.00508)
						(xy 0.22606 -0.00508) (xy 0.22733 -0.01651) (xy 0.22733 -0.02667) (xy 0.2286 -0.0381) (xy 0.22733 -0.04953)
						(xy 0.22733 -0.05969) (xy 0.22606 -0.07112) (xy 0.22352 -0.08128) (xy 0.22225 -0.09144) (xy 0.21844 -0.10287)
						(xy 0.2159 -0.11303) (xy 0.21209 -0.12319) (xy 0.20701 -0.13335) (xy 0.2032 -0.14224) (xy 0.19812 -0.1524)
						(xy 0.17272 -0.18796) (xy 0.1651 -0.19558) (xy 0.1651 -0.7366) (xy 0.16256 -0.76835) (xy 0.1524 -0.8001)
						(xy 0.13716 -0.82804) (xy 0.11684 -0.85344) (xy 0.09144 -0.87376) (xy 0.0635 -0.889) (xy 0.03175 -0.89916)
					)
					(width 0)
					(fill yes)
				)
			)
		)
		(pad "204" smd custom
			(at 31.649924 4.100068 180)
			(size 0.1143 0.1143)
			(layers "B.Cu" "B.Mask" "B.Paste")
			(net "PV_VTT_DDR_B")
			(options
				(clearance outline)
				(anchor circle)
			)
			(primitives
				(gr_poly
					(pts
						(xy 0 -0.9017) (xy -0.03175 -0.89916) (xy -0.0635 -0.889) (xy -0.09144 -0.87376) (xy -0.11684 -0.85344)
						(xy -0.13716 -0.82804) (xy -0.1524 -0.8001) (xy -0.16256 -0.76835) (xy -0.1651 -0.7366) (xy -0.1651 -0.11938)
						(xy -0.17272 -0.11176) (xy -0.19812 -0.0762) (xy -0.2032 -0.06604) (xy -0.20701 -0.05715) (xy -0.21209 -0.04699)
						(xy -0.2159 -0.03683) (xy -0.21844 -0.02667) (xy -0.22225 -0.01524) (xy -0.22352 -0.00508) (xy -0.22606 0.00508)
						(xy -0.22733 0.01651) (xy -0.22733 0.02667) (xy -0.2286 0.0381) (xy -0.22733 0.04953) (xy -0.22733 0.05969)
						(xy -0.22606 0.07112) (xy -0.22352 0.08128) (xy -0.22225 0.09144) (xy -0.21844 0.10287) (xy -0.2159 0.11303)
						(xy -0.21209 0.12319) (xy -0.20701 0.13335) (xy -0.2032 0.14224) (xy -0.19812 0.1524) (xy -0.17272 0.18796)
						(xy -0.1651 0.19558) (xy -0.1651 0.7366) (xy -0.16256 0.76835) (xy -0.1524 0.8001) (xy -0.13716 0.82804)
						(xy -0.11684 0.85344) (xy -0.09144 0.87376) (xy -0.0635 0.889) (xy -0.03175 0.89916) (xy 0 0.9017)
						(xy 0.03175 0.89916) (xy 0.0635 0.889) (xy 0.09144 0.87376) (xy 0.11684 0.85344) (xy 0.13716 0.82804)
						(xy 0.1524 0.8001) (xy 0.16256 0.76835) (xy 0.1651 0.7366) (xy 0.1651 0.19685) (xy 0.17272 0.18923)
						(xy 0.17907 0.18034) (xy 0.18669 0.17145) (xy 0.19177 0.16256) (xy 0.19812 0.15367) (xy 0.20828 0.13335)
						(xy 0.21971 0.10287) (xy 0.22225 0.09271) (xy 0.22479 0.08128) (xy 0.22606 0.07112) (xy 0.2286 0.05969)
						(xy 0.2286 0.01651) (xy 0.22606 0.00508) (xy 0.22479 -0.00508) (xy 0.22225 -0.01651) (xy 0.21971 -0.02667)
						(xy 0.20828 -0.05715) (xy 0.19812 -0.07747) (xy 0.19177 -0.08636) (xy 0.18669 -0.09525) (xy 0.17907 -0.10414)
						(xy 0.17272 -0.11303) (xy 0.1651 -0.12065) (xy 0.1651 -0.7366) (xy 0.16256 -0.76835) (xy 0.1524 -0.8001)
						(xy 0.13716 -0.82804) (xy 0.11684 -0.85344) (xy 0.09144 -0.87376) (xy 0.0635 -0.889) (xy 0.03175 -0.89916)
					)
					(width 0)
					(fill yes)
				)
			)
		)
		(pad "205" smd rect
			(at 37.450014 -11.999976 180)
			(size 4.4958 4.5974)
			(layers "B.Cu" "B.Mask" "B.Paste")
			(net "GND")
		)
		(pad "206" smd rect
			(at 32.800036 -11.999976 180)
			(size 3.5052 4.5974)
			(layers "B.Cu" "B.Mask" "B.Paste")
			(net "GND")
		)
		(pad "207" smd rect
			(at -32.800036 -11.999976 180)
			(size 3.5052 4.5974)
			(layers "B.Cu" "B.Mask" "B.Paste")
			(net "GND")
		)
		(pad "208" smd rect
			(at -37.450014 -11.999976 180)
			(size 4.4958 4.5974)
			(layers "B.Cu" "B.Mask" "B.Paste")
			(net "GND")
		)
	)
)
